# T6G (Grand Teton) — schematic netlist excerpt (pin names and nets, part order shuffled) for the footprints in the layout excerpt that follows; sources: Cadence DE-HDL packaged netlist, KiCad conversion of 04192023_DAF0TMB3IC0_F0TG_MB_C_brd_V02_OCP.brd

C6602  Q_CAP_DIFFBUS  DIFF BUS_0.22UF 6.3V 20% X6S  pkg C0201  page 308 : \1\ = P5E_CPU0_P3_TX_BUF_C_DN<2> ; \2\ = P5E_CPU0_P3_TX_BUF_DN<2>
C2502  Q_CAP  22UF 4V 20% X6S  pkg C0402  page 74 : A = PVDD11_S3_P1 ; B = GND
R2934  Q_RES  100K 1% CHIP  pkg 0402LF  page 127 : A = P3V3_AUX ; B = FM_SWB_PWRGD_ISO

(kicad_pcb
	(version 20260206)
	(generator "pcbnew")
	(generator_version "10.0")
	(general
		(thickness 1.6)
		(legacy_teardrops no)
	)
	(paper "A4")
	(title_block
		(title "04192023_DAF0TMB3IC0_F0TG_MB_C_brd_V02_OCP.brd")
		(comment 1 "Grand Teton / footprints 7003-7005 of 8354")
	)
	(layers
		(0 "F.Cu" signal "TOP")
		(4 "In1.Cu" signal "GND")
		(6 "In2.Cu" signal "IN1")
		(8 "In3.Cu" signal "GND1")
		(10 "In4.Cu" signal "IN2")
		(12 "In5.Cu" signal "GND2")
		(14 "In6.Cu" signal "IN3")
		(16 "In7.Cu" signal "GND3")
		(18 "In8.Cu" signal "VCC")
		(20 "In9.Cu" signal "VCC1")
		(22 "In10.Cu" signal "GND4")
		(24 "In11.Cu" signal "IN4")
		(26 "In12.Cu" signal "GND5")
		(28 "In13.Cu" signal "IN5")
		(30 "In14.Cu" signal "GND6")
		(32 "In15.Cu" signal "IN6")
		(34 "In16.Cu" signal "GND7")
		(2 "B.Cu" signal "BOTTOM")
		(9 "F.Adhes" user "F.Adhesive")
		(11 "B.Adhes" user "B.Adhesive")
		(13 "F.Paste" user "Package Geometry/Pastemask Top")
		(15 "B.Paste" user "Package Geometry/Pastemask Bottom")
		(5 "F.SilkS" user "Ref Des/Silkscreen Top")
		(7 "B.SilkS" user "Ref Des/Silkscreen Bottom")
		(1 "F.Mask" user "Board Geometry/Soldermask Top")
		(3 "B.Mask" user "Board Geometry/Soldermask Bottom")
		(17 "Dwgs.User" user "User.Drawings")
		(19 "Cmts.User" user "User.Comments")
		(21 "Eco1.User" user "User.Eco1")
		(23 "Eco2.User" user "User.Eco2")
		(25 "Edge.Cuts" user "Board Geometry/Outline")
		(27 "Margin" user)
		(31 "F.CrtYd" user "Package Geometry/Place Bound Top")
		(29 "B.CrtYd" user "Package Geometry/Place Bound Bottom")
		(35 "F.Fab" user "Ref Des/Assembly Top")
		(33 "B.Fab" user "Ref Des/Assembly Bottom")
	)
	(footprint ""
		(layer "B.Cu")
		(at 110.856014 -259.845302 180)
		(property "Reference" "C2502"
			(at 0 0 0)
			(layer "B.SilkS")
			(hide yes)
			(effects
				(font
					(size 1.27 1.27)
				)
				(justify mirror)
			)
		)
		(property "Value" ""
			(at 0 0 0)
			(layer "B.Fab")
			(effects
				(font
					(size 1.27 1.27)
				)
				(justify mirror)
			)
		)
		(duplicate_pad_numbers_are_jumpers no)
		(fp_line
			(start 0.7874 0.4064)
			(end 0.7874 -0.4064)
			(stroke
				(width 0.1524)
				(type default)
			)
			(layer "B.SilkS")
		)
		(fp_line
			(start 0.7874 -0.4064)
			(end -0.7874 -0.4064)
			(stroke
				(width 0.1524)
				(type default)
			)
			(layer "B.SilkS")
		)
		(fp_line
			(start -0.7874 0.4064)
			(end 0.7874 0.4064)
			(stroke
				(width 0.1524)
				(type default)
			)
			(layer "B.SilkS")
		)
		(fp_line
			(start -0.7874 -0.4064)
			(end -0.7874 0.4064)
			(stroke
				(width 0.1524)
				(type default)
			)
			(layer "B.SilkS")
		)
		(fp_line
			(start 0.67945 0.3048)
			(end 0.67945 -0.305054)
			(stroke
				(width 0.1)
				(type default)
			)
			(layer "B.Fab")
		)
		(fp_line
			(start 0.67945 -0.305054)
			(end 0.12065 -0.305054)
			(stroke
				(width 0.1)
				(type default)
			)
			(layer "B.Fab")
		)
		(fp_line
			(start 0.12065 0.3048)
			(end 0.67945 0.3048)
			(stroke
				(width 0.1)
				(type default)
			)
			(layer "B.Fab")
		)
		(fp_line
			(start 0.12065 0.2794)
			(end 0.12065 0.3048)
			(stroke
				(width 0.1)
				(type default)
			)
			(layer "B.Fab")
		)
		(fp_line
			(start 0.12065 -0.2794)
			(end -0.12065 -0.2794)
			(stroke
				(width 0.1)
				(type default)
			)
			(layer "B.Fab")
		)
		(fp_line
			(start 0.12065 -0.305054)
			(end 0.12065 -0.2794)
			(stroke
				(width 0.1)
				(type default)
			)
			(layer "B.Fab")
		)
		(fp_line
			(start -0.120396 0.3048)
			(end -0.120396 0.2794)
			(stroke
				(width 0.1)
				(type default)
			)
			(layer "B.Fab")
		)
		(fp_line
			(start -0.120396 0.2794)
			(end 0.12065 0.2794)
			(stroke
				(width 0.1)
				(type default)
			)
			(layer "B.Fab")
		)
		(fp_line
			(start -0.12065 -0.2794)
			(end -0.12065 -0.3048)
			(stroke
				(width 0.1)
				(type default)
			)
			(layer "B.Fab")
		)
		(fp_line
			(start -0.12065 -0.3048)
			(end -0.67945 -0.3048)
			(stroke
				(width 0.1)
				(type default)
			)
			(layer "B.Fab")
		)
		(fp_line
			(start -0.67945 0.3048)
			(end -0.120396 0.3048)
			(stroke
				(width 0.1)
				(type default)
			)
			(layer "B.Fab")
		)
		(fp_line
			(start -0.67945 -0.3048)
			(end -0.67945 0.3048)
			(stroke
				(width 0.1)
				(type default)
			)
			(layer "B.Fab")
		)
		(pad "1" smd circle
			(at 0.40005 0)
			(size 0 0)
			(layers "B.Cu" "B.Mask" "B.Paste")
			(net "PVDD11_S3_P1")
		)
		(pad "2" smd circle
			(at -0.40005 0)
			(size 0 0)
			(layers "B.Cu" "B.Mask" "B.Paste")
			(net "GND")
		)
	)
	(footprint ""
		(layer "B.Cu")
		(at 358.037892 -416.91687 180)
		(property "Reference" "R2934"
			(at 0 0 0)
			(layer "B.SilkS")
			(hide yes)
			(effects
				(font
					(size 1.27 1.27)
				)
				(justify mirror)
			)
		)
		(property "Value" ""
			(at 0 0 0)
			(layer "B.Fab")
			(effects
				(font
					(size 1.27 1.27)
				)
				(justify mirror)
			)
		)
		(duplicate_pad_numbers_are_jumpers no)
		(fp_line
			(start 0.7874 0.4064)
			(end 0.7874 -0.4064)
			(stroke
				(width 0.1524)
				(type default)
			)
			(layer "B.SilkS")
		)
		(fp_line
			(start 0.7874 -0.4064)
			(end -0.7874 -0.4064)
			(stroke
				(width 0.1524)
				(type default)
			)
			(layer "B.SilkS")
		)
		(fp_line
			(start -0.7874 0.4064)
			(end 0.7874 0.4064)
			(stroke
				(width 0.1524)
				(type default)
			)
			(layer "B.SilkS")
		)
		(fp_line
			(start -0.7874 -0.4064)
			(end -0.7874 0.4064)
			(stroke
				(width 0.1524)
				(type default)
			)
			(layer "B.SilkS")
		)
		(fp_line
			(start 0.67945 0.3048)
			(end 0.67945 -0.305054)
			(stroke
				(width 0.1)
				(type default)
			)
			(layer "B.Fab")
		)
		(fp_line
			(start 0.67945 -0.305054)
			(end 0.12065 -0.305054)
			(stroke
				(width 0.1)
				(type default)
			)
			(layer "B.Fab")
		)
		(fp_line
			(start 0.12065 0.3048)
			(end 0.67945 0.3048)
			(stroke
				(width 0.1)
				(type default)
			)
			(layer "B.Fab")
		)
		(fp_line
			(start 0.12065 0.2794)
			(end 0.12065 0.3048)
			(stroke
				(width 0.1)
				(type default)
			)
			(layer "B.Fab")
		)
		(fp_line
			(start 0.12065 -0.2794)
			(end -0.12065 -0.2794)
			(stroke
				(width 0.1)
				(type default)
			)
			(layer "B.Fab")
		)
		(fp_line
			(start 0.12065 -0.305054)
			(end 0.12065 -0.2794)
			(stroke
				(width 0.1)
				(type default)
			)
			(layer "B.Fab")
		)
		(fp_line
			(start -0.120396 0.3048)
			(end -0.120396 0.2794)
			(stroke
				(width 0.1)
				(type default)
			)
			(layer "B.Fab")
		)
		(fp_line
			(start -0.120396 0.2794)
			(end 0.12065 0.2794)
			(stroke
				(width 0.1)
				(type default)
			)
			(layer "B.Fab")
		)
		(fp_line
			(start -0.12065 -0.2794)
			(end -0.12065 -0.3048)
			(stroke
				(width 0.1)
				(type default)
			)
			(layer "B.Fab")
		)
		(fp_line
			(start -0.12065 -0.3048)
			(end -0.67945 -0.3048)
			(stroke
				(width 0.1)
				(type default)
			)
			(layer "B.Fab")
		)
		(fp_line
			(start -0.67945 0.3048)
			(end -0.120396 0.3048)
			(stroke
				(width 0.1)
				(type default)
			)
			(layer "B.Fab")
		)
		(fp_line
			(start -0.67945 -0.3048)
			(end -0.67945 0.3048)
			(stroke
				(width 0.1)
				(type default)
			)
			(layer "B.Fab")
		)
		(pad "1" smd circle
			(at 0.40005 0)
			(size 0 0)
			(layers "B.Cu" "B.Mask" "B.Paste")
			(net "P3V3_AUX")
		)
		(pad "2" smd circle
			(at -0.40005 0)
			(size 0 0)
			(layers "B.Cu" "B.Mask" "B.Paste")
			(net "FM_SWB_PWRGD_ISO")
		)
	)
	(footprint ""
		(layer "B.Cu")
		(at 378.526802 -416.899344 90)
		(property "Reference" "C6602"
			(at 0 0 90)
			(layer "B.SilkS")
			(hide yes)
			(effects
				(font
					(size 1.27 1.27)
				)
				(justify mirror)
			)
		)
		(property "Value" ""
			(at 0 0 90)
			(layer "B.Fab")
			(effects
				(font
					(size 1.27 1.27)
				)
				(justify mirror)
			)
		)
		(duplicate_pad_numbers_are_jumpers no)
		(fp_line
			(start 0.299974 -0.150114)
			(end -0.299974 -0.150114)
			(stroke
				(width 0.1)
				(type default)
			)
			(layer "B.Fab")
		)
		(fp_line
			(start -0.299974 -0.150114)
			(end -0.299974 0.150114)
			(stroke
				(width 0.1)
				(type default)
			)
			(layer "B.Fab")
		)
		(fp_line
			(start 0.299974 0.150114)
			(end 0.299974 -0.150114)
			(stroke
				(width 0.1)
				(type default)
			)
			(layer "B.Fab")
		)
		(fp_line
			(start -0.299974 0.150114)
			(end 0.299974 0.150114)
			(stroke
				(width 0.1)
				(type default)
			)
			(layer "B.Fab")
		)
		(pad "1" smd rect
			(at 0.2667 0 270)
			(size 0.3048 0.381)
			(layers "B.Cu" "B.Mask" "B.Paste")
			(net "P5E_CPU0_P3_TX_BUF_C_DN<2>")
		)
		(pad "2" smd rect
			(at -0.2667 0 270)
			(size 0.3048 0.381)
			(layers "B.Cu" "B.Mask" "B.Paste")
			(net "P5E_CPU0_P3_TX_BUF_DN<2>")
		)
	)
)
